(kicad_pcb
	(version 20260206)
	(generator "pcbnew")
	(generator_version "10.0")
	(general
		(thickness 1.6)
		(legacy_teardrops no)
	)
	(paper "A4")
	(title_block
		(title "03242023_DA0F0TMBIJ0_F0T_Motherboard_J_brd_V01_OCP.brd")
		(comment 1 "Grand Teton / footprints 4384-4390 of 6105")
	)
	(layers
		(0 "F.Cu" signal "TOP")
		(4 "In1.Cu" signal "GND")
		(6 "In2.Cu" signal "IN1")
		(8 "In3.Cu" signal "GND1")
		(10 "In4.Cu" signal "IN2")
		(12 "In5.Cu" signal "GND2")
		(14 "In6.Cu" signal "IN3")
		(16 "In7.Cu" signal "GND3")
		(18 "In8.Cu" signal "VCC")
		(20 "In9.Cu" signal "VCC1")
		(22 "In10.Cu" signal "GND4")
		(24 "In11.Cu" signal "IN4")
		(26 "In12.Cu" signal "GND5")
		(28 "In13.Cu" signal "IN5")
		(30 "In14.Cu" signal "GND6")
		(32 "In15.Cu" signal "IN6")
		(34 "In16.Cu" signal "GND7")
		(2 "B.Cu" signal "BOTTOM")
		(9 "F.Adhes" user "F.Adhesive")
		(11 "B.Adhes" user "B.Adhesive")
		(13 "F.Paste" user "Package Geometry/Pastemask Top")
		(15 "B.Paste" user "Package Geometry/Pastemask Bottom")
		(5 "F.SilkS" user "Ref Des/Silkscreen Top")
		(7 "B.SilkS" user "Ref Des/Silkscreen Bottom")
		(1 "F.Mask" user "Board Geometry/Soldermask Top")
		(3 "B.Mask" user "Board Geometry/Soldermask Bottom")
		(17 "Dwgs.User" user "User.Drawings")
		(19 "Cmts.User" user "User.Comments")
		(21 "Eco1.User" user "User.Eco1")
		(23 "Eco2.User" user "User.Eco2")
		(25 "Edge.Cuts" user "Board Geometry/Outline")
		(27 "Margin" user)
		(31 "F.CrtYd" user "Package Geometry/Place Bound Top")
		(29 "B.CrtYd" user "Package Geometry/Place Bound Bottom")
		(35 "F.Fab" user "Ref Des/Assembly Top")
		(33 "B.Fab" user "Ref Des/Assembly Bottom")
	)
	(footprint ""
		(layer "B.Cu")
		(at 92.177108 -190.705232 -90)
		(property "Reference" "R662"
			(at 0 0 90)
			(layer "B.SilkS")
			(hide yes)
			(effects
				(font
					(size 1.27 1.27)
				)
				(justify mirror)
			)
		)
		(property "Value" ""
			(at 0 0 90)
			(layer "B.Fab")
			(effects
				(font
					(size 1.27 1.27)
				)
				(justify mirror)
			)
		)
		(duplicate_pad_numbers_are_jumpers no)
		(fp_line
			(start -0.7874 0.4064)
			(end 0.7874 0.4064)
			(stroke
				(width 0.1524)
				(type default)
			)
			(layer "B.SilkS")
		)
		(fp_line
			(start 0.7874 0.4064)
			(end 0.7874 -0.4064)
			(stroke
				(width 0.1524)
				(type default)
			)
			(layer "B.SilkS")
		)
		(fp_line
			(start -0.7874 -0.4064)
			(end -0.7874 0.4064)
			(stroke
				(width 0.1524)
				(type default)
			)
			(layer "B.SilkS")
		)
		(fp_line
			(start 0.7874 -0.4064)
			(end -0.7874 -0.4064)
			(stroke
				(width 0.1524)
				(type default)
			)
			(layer "B.SilkS")
		)
		(fp_line
			(start -0.67945 0.3048)
			(end -0.120396 0.3048)
			(stroke
				(width 0.1)
				(type default)
			)
			(layer "B.Fab")
		)
		(fp_line
			(start -0.120396 0.3048)
			(end -0.120396 0.2794)
			(stroke
				(width 0.1)
				(type default)
			)
			(layer "B.Fab")
		)
		(fp_line
			(start 0.12065 0.3048)
			(end 0.67945 0.3048)
			(stroke
				(width 0.1)
				(type default)
			)
			(layer "B.Fab")
		)
		(fp_line
			(start 0.67945 0.3048)
			(end 0.67945 -0.305054)
			(stroke
				(width 0.1)
				(type default)
			)
			(layer "B.Fab")
		)
		(fp_line
			(start -0.120396 0.2794)
			(end 0.12065 0.2794)
			(stroke
				(width 0.1)
				(type default)
			)
			(layer "B.Fab")
		)
		(fp_line
			(start 0.12065 0.2794)
			(end 0.12065 0.3048)
			(stroke
				(width 0.1)
				(type default)
			)
			(layer "B.Fab")
		)
		(fp_line
			(start -0.12065 -0.2794)
			(end -0.12065 -0.3048)
			(stroke
				(width 0.1)
				(type default)
			)
			(layer "B.Fab")
		)
		(fp_line
			(start 0.12065 -0.2794)
			(end -0.12065 -0.2794)
			(stroke
				(width 0.1)
				(type default)
			)
			(layer "B.Fab")
		)
		(fp_line
			(start -0.67945 -0.3048)
			(end -0.67945 0.3048)
			(stroke
				(width 0.1)
				(type default)
			)
			(layer "B.Fab")
		)
		(fp_line
			(start -0.12065 -0.3048)
			(end -0.67945 -0.3048)
			(stroke
				(width 0.1)
				(type default)
			)
			(layer "B.Fab")
		)
		(fp_line
			(start 0.12065 -0.305054)
			(end 0.12065 -0.2794)
			(stroke
				(width 0.1)
				(type default)
			)
			(layer "B.Fab")
		)
		(fp_line
			(start 0.67945 -0.305054)
			(end 0.12065 -0.305054)
			(stroke
				(width 0.1)
				(type default)
			)
			(layer "B.Fab")
		)
		(pad "1" smd circle
			(at 0.40005 0 90)
			(size 0 0)
			(layers "B.Cu" "B.Mask" "B.Paste")
			(net "PVNN_TERM_CPU1")
		)
		(pad "2" smd circle
			(at -0.40005 0 90)
			(size 0 0)
			(layers "B.Cu" "B.Mask" "B.Paste")
			(net "I3C_SPD_DDRABCD_CPU1_SCL")
		)
	)
	(footprint ""
		(layer "B.Cu")
		(at 440.08802 -20.412456)
		(property "Reference" "PC2080"
			(at 0 0 0)
			(layer "B.SilkS")
			(hide yes)
			(effects
				(font
					(size 1.27 1.27)
				)
				(justify mirror)
			)
		)
		(property "Value" ""
			(at 0 0 0)
			(layer "B.Fab")
			(effects
				(font
					(size 1.27 1.27)
				)
				(justify mirror)
			)
		)
		(duplicate_pad_numbers_are_jumpers no)
		(fp_line
			(start -1.524 -0.762)
			(end -1.524 0.762)
			(stroke
				(width 0.1524)
				(type default)
			)
			(layer "B.SilkS")
		)
		(fp_line
			(start -1.524 0.762)
			(end 1.524 0.762)
			(stroke
				(width 0.1524)
				(type default)
			)
			(layer "B.SilkS")
		)
		(fp_line
			(start 1.524 -0.762)
			(end -1.524 -0.762)
			(stroke
				(width 0.1524)
				(type default)
			)
			(layer "B.SilkS")
		)
		(fp_line
			(start 1.524 0.762)
			(end 1.524 -0.762)
			(stroke
				(width 0.1524)
				(type default)
			)
			(layer "B.SilkS")
		)
		(fp_line
			(start -1.1049 -0.724916)
			(end 1.1049 -0.724916)
			(stroke
				(width 0.1)
				(type default)
			)
			(layer "B.Fab")
		)
		(fp_line
			(start -1.1049 0.724916)
			(end -1.1049 -0.724916)
			(stroke
				(width 0.1)
				(type default)
			)
			(layer "B.Fab")
		)
		(fp_line
			(start 1.1049 -0.724916)
			(end 1.1049 0.724916)
			(stroke
				(width 0.1)
				(type default)
			)
			(layer "B.Fab")
		)
		(fp_line
			(start 1.1049 0.724916)
			(end -1.1049 0.724916)
			(stroke
				(width 0.1)
				(type default)
			)
			(layer "B.Fab")
		)
		(pad "1" smd rect
			(at 0.889 0)
			(size 1.016 1.27)
			(layers "B.Cu" "B.Mask" "B.Paste")
			(net "P12V_OCP_SFF")
		)
		(pad "2" smd rect
			(at -0.889 0)
			(size 1.016 1.27)
			(layers "B.Cu" "B.Mask" "B.Paste")
			(net "GND")
		)
	)
	(footprint ""
		(layer "B.Cu")
		(at 64.990218 -317.897256 180)
		(property "Reference" "R2494"
			(at 0 0 0)
			(layer "B.SilkS")
			(hide yes)
			(effects
				(font
					(size 1.27 1.27)
				)
				(justify mirror)
			)
		)
		(property "Value" ""
			(at 0 0 0)
			(layer "B.Fab")
			(effects
				(font
					(size 1.27 1.27)
				)
				(justify mirror)
			)
		)
		(duplicate_pad_numbers_are_jumpers no)
		(fp_line
			(start 0.7874 0.4064)
			(end 0.7874 -0.4064)
			(stroke
				(width 0.1524)
				(type default)
			)
			(layer "B.SilkS")
		)
		(fp_line
			(start 0.7874 -0.4064)
			(end -0.7874 -0.4064)
			(stroke
				(width 0.1524)
				(type default)
			)
			(layer "B.SilkS")
		)
		(fp_line
			(start -0.7874 0.4064)
			(end 0.7874 0.4064)
			(stroke
				(width 0.1524)
				(type default)
			)
			(layer "B.SilkS")
		)
		(fp_line
			(start -0.7874 -0.4064)
			(end -0.7874 0.4064)
			(stroke
				(width 0.1524)
				(type default)
			)
			(layer "B.SilkS")
		)
		(fp_line
			(start 0.67945 0.3048)
			(end 0.67945 -0.305054)
			(stroke
				(width 0.1)
				(type default)
			)
			(layer "B.Fab")
		)
		(fp_line
			(start 0.67945 -0.305054)
			(end 0.12065 -0.305054)
			(stroke
				(width 0.1)
				(type default)
			)
			(layer "B.Fab")
		)
		(fp_line
			(start 0.12065 0.3048)
			(end 0.67945 0.3048)
			(stroke
				(width 0.1)
				(type default)
			)
			(layer "B.Fab")
		)
		(fp_line
			(start 0.12065 0.2794)
			(end 0.12065 0.3048)
			(stroke
				(width 0.1)
				(type default)
			)
			(layer "B.Fab")
		)
		(fp_line
			(start 0.12065 -0.2794)
			(end -0.12065 -0.2794)
			(stroke
				(width 0.1)
				(type default)
			)
			(layer "B.Fab")
		)
		(fp_line
			(start 0.12065 -0.305054)
			(end 0.12065 -0.2794)
			(stroke
				(width 0.1)
				(type default)
			)
			(layer "B.Fab")
		)
		(fp_line
			(start -0.120396 0.3048)
			(end -0.120396 0.2794)
			(stroke
				(width 0.1)
				(type default)
			)
			(layer "B.Fab")
		)
		(fp_line
			(start -0.120396 0.2794)
			(end 0.12065 0.2794)
			(stroke
				(width 0.1)
				(type default)
			)
			(layer "B.Fab")
		)
		(fp_line
			(start -0.12065 -0.2794)
			(end -0.12065 -0.3048)
			(stroke
				(width 0.1)
				(type default)
			)
			(layer "B.Fab")
		)
		(fp_line
			(start -0.12065 -0.3048)
			(end -0.67945 -0.3048)
			(stroke
				(width 0.1)
				(type default)
			)
			(layer "B.Fab")
		)
		(fp_line
			(start -0.67945 0.3048)
			(end -0.120396 0.3048)
			(stroke
				(width 0.1)
				(type default)
			)
			(layer "B.Fab")
		)
		(fp_line
			(start -0.67945 -0.3048)
			(end -0.67945 0.3048)
			(stroke
				(width 0.1)
				(type default)
			)
			(layer "B.Fab")
		)
		(pad "1" smd circle
			(at 0.40005 0)
			(size 0 0)
			(layers "B.Cu" "B.Mask" "B.Paste")
			(net "PWRGD_FAIL_CPU1_AB")
		)
		(pad "2" smd circle
			(at -0.40005 0)
			(size 0 0)
			(layers "B.Cu" "B.Mask" "B.Paste")
			(net "PWRGD_FAIL_CPU1_AB_R1")
		)
	)
	(footprint ""
		(layer "B.Cu")
		(at 170.673268 -196.013578 -90)
		(property "Reference" "R4302"
			(at 0 0 90)
			(layer "B.SilkS")
			(hide yes)
			(effects
				(font
					(size 1.27 1.27)
				)
				(justify mirror)
			)
		)
		(property "Value" ""
			(at 0 0 90)
			(layer "B.Fab")
			(effects
				(font
					(size 1.27 1.27)
				)
				(justify mirror)
			)
		)
		(duplicate_pad_numbers_are_jumpers no)
		(fp_line
			(start -0.7874 0.4064)
			(end 0.7874 0.4064)
			(stroke
				(width 0.1524)
				(type default)
			)
			(layer "B.SilkS")
		)
		(fp_line
			(start 0.7874 0.4064)
			(end 0.7874 -0.4064)
			(stroke
				(width 0.1524)
				(type default)
			)
			(layer "B.SilkS")
		)
		(fp_line
			(start -0.7874 -0.4064)
			(end -0.7874 0.4064)
			(stroke
				(width 0.1524)
				(type default)
			)
			(layer "B.SilkS")
		)
		(fp_line
			(start 0.7874 -0.4064)
			(end -0.7874 -0.4064)
			(stroke
				(width 0.1524)
				(type default)
			)
			(layer "B.SilkS")
		)
		(fp_line
			(start -0.67945 0.3048)
			(end -0.120396 0.3048)
			(stroke
				(width 0.1)
				(type default)
			)
			(layer "B.Fab")
		)
		(fp_line
			(start -0.120396 0.3048)
			(end -0.120396 0.2794)
			(stroke
				(width 0.1)
				(type default)
			)
			(layer "B.Fab")
		)
		(fp_line
			(start 0.12065 0.3048)
			(end 0.67945 0.3048)
			(stroke
				(width 0.1)
				(type default)
			)
			(layer "B.Fab")
		)
		(fp_line
			(start 0.67945 0.3048)
			(end 0.67945 -0.305054)
			(stroke
				(width 0.1)
				(type default)
			)
			(layer "B.Fab")
		)
		(fp_line
			(start -0.120396 0.2794)
			(end 0.12065 0.2794)
			(stroke
				(width 0.1)
				(type default)
			)
			(layer "B.Fab")
		)
		(fp_line
			(start 0.12065 0.2794)
			(end 0.12065 0.3048)
			(stroke
				(width 0.1)
				(type default)
			)
			(layer "B.Fab")
		)
		(fp_line
			(start -0.12065 -0.2794)
			(end -0.12065 -0.3048)
			(stroke
				(width 0.1)
				(type default)
			)
			(layer "B.Fab")
		)
		(fp_line
			(start 0.12065 -0.2794)
			(end -0.12065 -0.2794)
			(stroke
				(width 0.1)
				(type default)
			)
			(layer "B.Fab")
		)
		(fp_line
			(start -0.67945 -0.3048)
			(end -0.67945 0.3048)
			(stroke
				(width 0.1)
				(type default)
			)
			(layer "B.Fab")
		)
		(fp_line
			(start -0.12065 -0.3048)
			(end -0.67945 -0.3048)
			(stroke
				(width 0.1)
				(type default)
			)
			(layer "B.Fab")
		)
		(fp_line
			(start 0.12065 -0.305054)
			(end 0.12065 -0.2794)
			(stroke
				(width 0.1)
				(type default)
			)
			(layer "B.Fab")
		)
		(fp_line
			(start 0.67945 -0.305054)
			(end 0.12065 -0.305054)
			(stroke
				(width 0.1)
				(type default)
			)
			(layer "B.Fab")
		)
		(pad "1" smd circle
			(at 0.40005 0 90)
			(size 0 0)
			(layers "B.Cu" "B.Mask" "B.Paste")
			(net "PWRGD_DRAMPWRGD_CPU1_GH_LVC1_R2")
		)
		(pad "2" smd circle
			(at -0.40005 0 90)
			(size 0 0)
			(layers "B.Cu" "B.Mask" "B.Paste")
			(net "PWRGD_DRAMPWRGD_CPU1_GH_LVC1_R")
		)
	)
	(footprint ""
		(layer "B.Cu")
		(at 89.958926 -337.145884 90)
		(property "Reference" "PC515_P1_6"
			(at 0 0 90)
			(layer "B.SilkS")
			(hide yes)
			(effects
				(font
					(size 1.27 1.27)
				)
				(justify mirror)
			)
		)
		(property "Value" ""
			(at 0 0 90)
			(layer "B.Fab")
			(effects
				(font
					(size 1.27 1.27)
				)
				(justify mirror)
			)
		)
		(duplicate_pad_numbers_are_jumpers no)
		(fp_line
			(start 1.524 -0.762)
			(end -1.524 -0.762)
			(stroke
				(width 0.1524)
				(type default)
			)
			(layer "B.SilkS")
		)
		(fp_line
			(start -1.524 -0.762)
			(end -1.524 0.762)
			(stroke
				(width 0.1524)
				(type default)
			)
			(layer "B.SilkS")
		)
		(fp_line
			(start 1.524 0.762)
			(end 1.524 -0.762)
			(stroke
				(width 0.1524)
				(type default)
			)
			(layer "B.SilkS")
		)
		(fp_line
			(start -1.524 0.762)
			(end 1.524 0.762)
			(stroke
				(width 0.1524)
				(type default)
			)
			(layer "B.SilkS")
		)
		(fp_line
			(start 1.1049 -0.724916)
			(end 1.1049 0.724916)
			(stroke
				(width 0.1)
				(type default)
			)
			(layer "B.Fab")
		)
		(fp_line
			(start -1.1049 -0.724916)
			(end 1.1049 -0.724916)
			(stroke
				(width 0.1)
				(type default)
			)
			(layer "B.Fab")
		)
		(fp_line
			(start 1.1049 0.724916)
			(end -1.1049 0.724916)
			(stroke
				(width 0.1)
				(type default)
			)
			(layer "B.Fab")
		)
		(fp_line
			(start -1.1049 0.724916)
			(end -1.1049 -0.724916)
			(stroke
				(width 0.1)
				(type default)
			)
			(layer "B.Fab")
		)
		(pad "1" smd rect
			(at 0.889 0 90)
			(size 1.016 1.27)
			(layers "B.Cu" "B.Mask" "B.Paste")
			(net "SW_P12V_PVCCIN_CPU1_FLT")
		)
		(pad "2" smd rect
			(at -0.889 0 90)
			(size 1.016 1.27)
			(layers "B.Cu" "B.Mask" "B.Paste")
			(net "GND")
		)
	)
	(footprint ""
		(layer "B.Cu")
		(at 76.809854 -345.830144 -90)
		(property "Reference" "PR290"
			(at 0 0 90)
			(layer "B.SilkS")
			(hide yes)
			(effects
				(font
					(size 1.27 1.27)
				)
				(justify mirror)
			)
		)
		(property "Value" ""
			(at 0 0 90)
			(layer "B.Fab")
			(effects
				(font
					(size 1.27 1.27)
				)
				(justify mirror)
			)
		)
		(duplicate_pad_numbers_are_jumpers no)
		(fp_line
			(start -0.7874 0.4064)
			(end 0.7874 0.4064)
			(stroke
				(width 0.1524)
				(type default)
			)
			(layer "B.SilkS")
		)
		(fp_line
			(start 0.7874 0.4064)
			(end 0.7874 -0.4064)
			(stroke
				(width 0.1524)
				(type default)
			)
			(layer "B.SilkS")
		)
		(fp_line
			(start -0.7874 -0.4064)
			(end -0.7874 0.4064)
			(stroke
				(width 0.1524)
				(type default)
			)
			(layer "B.SilkS")
		)
		(fp_line
			(start 0.7874 -0.4064)
			(end -0.7874 -0.4064)
			(stroke
				(width 0.1524)
				(type default)
			)
			(layer "B.SilkS")
		)
		(fp_line
			(start -0.67945 0.3048)
			(end -0.120396 0.3048)
			(stroke
				(width 0.1)
				(type default)
			)
			(layer "B.Fab")
		)
		(fp_line
			(start -0.120396 0.3048)
			(end -0.120396 0.2794)
			(stroke
				(width 0.1)
				(type default)
			)
			(layer "B.Fab")
		)
		(fp_line
			(start 0.12065 0.3048)
			(end 0.67945 0.3048)
			(stroke
				(width 0.1)
				(type default)
			)
			(layer "B.Fab")
		)
		(fp_line
			(start 0.67945 0.3048)
			(end 0.67945 -0.305054)
			(stroke
				(width 0.1)
				(type default)
			)
			(layer "B.Fab")
		)
		(fp_line
			(start -0.120396 0.2794)
			(end 0.12065 0.2794)
			(stroke
				(width 0.1)
				(type default)
			)
			(layer "B.Fab")
		)
		(fp_line
			(start 0.12065 0.2794)
			(end 0.12065 0.3048)
			(stroke
				(width 0.1)
				(type default)
			)
			(layer "B.Fab")
		)
		(fp_line
			(start -0.12065 -0.2794)
			(end -0.12065 -0.3048)
			(stroke
				(width 0.1)
				(type default)
			)
			(layer "B.Fab")
		)
		(fp_line
			(start 0.12065 -0.2794)
			(end -0.12065 -0.2794)
			(stroke
				(width 0.1)
				(type default)
			)
			(layer "B.Fab")
		)
		(fp_line
			(start -0.67945 -0.3048)
			(end -0.67945 0.3048)
			(stroke
				(width 0.1)
				(type default)
			)
			(layer "B.Fab")
		)
		(fp_line
			(start -0.12065 -0.3048)
			(end -0.67945 -0.3048)
			(stroke
				(width 0.1)
				(type default)
			)
			(layer "B.Fab")
		)
		(fp_line
			(start 0.12065 -0.305054)
			(end 0.12065 -0.2794)
			(stroke
				(width 0.1)
				(type default)
			)
			(layer "B.Fab")
		)
		(fp_line
			(start 0.67945 -0.305054)
			(end 0.12065 -0.305054)
			(stroke
				(width 0.1)
				(type default)
			)
			(layer "B.Fab")
		)
		(pad "1" smd circle
			(at 0.40005 0 90)
			(size 0 0)
			(layers "B.Cu" "B.Mask" "B.Paste")
			(net "PVCCIN_CPU1_VOS7")
		)
		(pad "2" smd circle
			(at -0.40005 0 90)
			(size 0 0)
			(layers "B.Cu" "B.Mask" "B.Paste")
			(net "PVCCIN_CPU1")
		)
	)
	(footprint ""
		(layer "B.Cu")
		(at 178.689 -19.522948 -90)
		(property "Reference" "R4504"
			(at 0 0 90)
			(layer "B.SilkS")
			(hide yes)
			(effects
				(font
					(size 1.27 1.27)
				)
				(justify mirror)
			)
		)
		(property "Value" ""
			(at 0 0 90)
			(layer "B.Fab")
			(effects
				(font
					(size 1.27 1.27)
				)
				(justify mirror)
			)
		)
		(duplicate_pad_numbers_are_jumpers no)
		(fp_line
			(start -0.7874 0.4064)
			(end 0.7874 0.4064)
			(stroke
				(width 0.1524)
				(type default)
			)
			(layer "B.SilkS")
		)
		(fp_line
			(start 0.7874 0.4064)
			(end 0.7874 -0.4064)
			(stroke
				(width 0.1524)
				(type default)
			)
			(layer "B.SilkS")
		)
		(fp_line
			(start -0.7874 -0.4064)
			(end -0.7874 0.4064)
			(stroke
				(width 0.1524)
				(type default)
			)
			(layer "B.SilkS")
		)
		(fp_line
			(start 0.7874 -0.4064)
			(end -0.7874 -0.4064)
			(stroke
				(width 0.1524)
				(type default)
			)
			(layer "B.SilkS")
		)
		(fp_line
			(start -0.67945 0.3048)
			(end -0.120396 0.3048)
			(stroke
				(width 0.1)
				(type default)
			)
			(layer "B.Fab")
		)
		(fp_line
			(start -0.120396 0.3048)
			(end -0.120396 0.2794)
			(stroke
				(width 0.1)
				(type default)
			)
			(layer "B.Fab")
		)
		(fp_line
			(start 0.12065 0.3048)
			(end 0.67945 0.3048)
			(stroke
				(width 0.1)
				(type default)
			)
			(layer "B.Fab")
		)
		(fp_line
			(start 0.67945 0.3048)
			(end 0.67945 -0.305054)
			(stroke
				(width 0.1)
				(type default)
			)
			(layer "B.Fab")
		)
		(fp_line
			(start -0.120396 0.2794)
			(end 0.12065 0.2794)
			(stroke
				(width 0.1)
				(type default)
			)
			(layer "B.Fab")
		)
		(fp_line
			(start 0.12065 0.2794)
			(end 0.12065 0.3048)
			(stroke
				(width 0.1)
				(type default)
			)
			(layer "B.Fab")
		)
		(fp_line
			(start -0.12065 -0.2794)
			(end -0.12065 -0.3048)
			(stroke
				(width 0.1)
				(type default)
			)
			(layer "B.Fab")
		)
		(fp_line
			(start 0.12065 -0.2794)
			(end -0.12065 -0.2794)
			(stroke
				(width 0.1)
				(type default)
			)
			(layer "B.Fab")
		)
		(fp_line
			(start -0.67945 -0.3048)
			(end -0.67945 0.3048)
			(stroke
				(width 0.1)
				(type default)
			)
			(layer "B.Fab")
		)
		(fp_line
			(start -0.12065 -0.3048)
			(end -0.67945 -0.3048)
			(stroke
				(width 0.1)
				(type default)
			)
			(layer "B.Fab")
		)
		(fp_line
			(start 0.12065 -0.305054)
			(end 0.12065 -0.2794)
			(stroke
				(width 0.1)
				(type default)
			)
			(layer "B.Fab")
		)
		(fp_line
			(start 0.67945 -0.305054)
			(end 0.12065 -0.305054)
			(stroke
				(width 0.1)
				(type default)
			)
			(layer "B.Fab")
		)
		(pad "1" smd circle
			(at 0.40005 0 90)
			(size 0 0)
			(layers "B.Cu" "B.Mask" "B.Paste")
			(net "SMB_SML1_PMBUS_3V3AUX_PCH_SDA")
		)
		(pad "2" smd circle
			(at -0.40005 0 90)
			(size 0 0)
			(layers "B.Cu" "B.Mask" "B.Paste")
			(net "SMB_SML1_PMBUS_3V3AUX_PCH_SDA_1")
		)
	)
)
